#ISCELL
  mstr_misc dns *
  *
#ISCELL
  pure_quanta quanta_title_block_c *
  *
#ISCELL
  pure_quanta_power universal_power *
  page315_i1
#CELL
  pure_quanta q_cap *
  page315_i10
#ISCELL
  pure_quanta_power gnd *
  page315_i11
#CELL
  pure_quanta q_res *
  page315_i12
#CELL
  pure_quanta q_cap *
  page315_i13
#ISCELL
  pure_quanta_power gnd *
  page315_i14
#CELL
  pure_quanta q_res *
  page315_i15
#ISCELL
  pure_quanta_power gnd *
  page315_i17
#CELL
  pure_quanta mpq8626gdz *
  page315_i18
#CELL
  pure_quanta q_cap *
  page315_i19
#CELL
  pure_quanta q_res *
  page315_i2
#ISCELL
  pure_quanta_power gnd *
  page315_i20
#CELL
  pure_quanta q_cap *
  page315_i21
#ISCELL
  pure_quanta_power gnd *
  page315_i22
#CELL
  pure_quanta q_res *
  page315_i23
#ISCELL
  pure_quanta_power gnd *
  page315_i24
#CELL
  pure_quanta q_inductor *
  page315_i25
#CELL
  pure_quanta q_cap *
  page315_i26
#CELL
  pure_quanta q_cap *
  page315_i27
#CELL
  pure_quanta q_res *
  page315_i28
#CELL
  pure_quanta q_cap *
  page315_i29
#ISCELL
  pure_quanta_power gnd *
  page315_i3
#CELL
  pure_quanta q_cap *
  page315_i30
#CELL
  pure_quanta q_res *
  page315_i32
#ISCELL
  pure_quanta_power universal_power *
  page315_i33
#CELL
  pure_quanta q_cap *
  page315_i34
#ISCELL
  pure_quanta_power gnd *
  page315_i35
#CELL
  pure_quanta q_cap *
  page315_i36
#CELL
  pure_quanta q_cap *
  page315_i37
#ISCELL
  pure_quanta_power universal_power *
  page315_i38
#ISCELL
  standard offpage *
  page315_i39
#ISCELL
  pure_quanta_power gnd *
  page315_i4
#CELL
  pure_quanta q_res *
  page315_i40
#CELL
  pure_quanta q_cap *
  page315_i41
#ISCELL
  pure_quanta_power gnd *
  page315_i42
#ISCELL
  standard offpage *
  page315_i43
#CELL
  pure_quanta q_res *
  page315_i44
#CELL
  pure_quanta q_res *
  page315_i45
#CELL
  pure_quanta q_cap *
  page315_i5
#ISCELL
  pure_quanta_power universal_power *
  page315_i6
#CELL
  pure_quanta q_inductor *
  page315_i7
#CELL
  pure_quanta q_cap *
  page315_i8
#ISCELL
  pure_quanta_power gnd *
  page315_i9
